# BASEBOARD_FAB2 (Tioga Pass) — schematic netlist excerpt (pin names and nets, part order shuffled) for the footprints in the layout excerpt that follows; sources: Cadence DE-HDL packaged netlist, KiCad conversion of Wiwynn_Tioga_Pass_MB.brd

C2U14  CAP  0.22UF 16V 10% X7R  pkg 0402  page 107 : A = P3E_CPU0_PE1_PCH_RXN<5> ; B = P3E_CPU0_PE1_SS_RXN<5>
C6N2  CAP  10UF 16V 10% X6S  pkg 0805  page 205 : A = VR_FET_SW_P12V_STBY_PVCCIN_CPU0 ; B = GND
C5G109  CAP_A  22.0UF 4V 20% X6S  pkg 0603V  page 243 : A = PVDDQ_KLM ; B = GND

(kicad_pcb
	(version 20260206)
	(generator "pcbnew")
	(generator_version "10.0")
	(general
		(thickness 1.6)
		(legacy_teardrops no)
	)
	(paper "A4")
	(title_block
		(title "Wiwynn_Tioga_Pass_MB.brd")
		(comment 1 "Tioga Pass / footprints 4733-4735 of 4770")
	)
	(layers
		(0 "F.Cu" signal "TOP")
		(4 "In1.Cu" signal "L2GND")
		(6 "In2.Cu" signal "L3")
		(8 "In3.Cu" signal "L4GND")
		(10 "In4.Cu" signal "L5")
		(12 "In5.Cu" signal "L6GND")
		(14 "In6.Cu" signal "L7VCC")
		(16 "In7.Cu" signal "L8VCC")
		(18 "In8.Cu" signal "L9GND")
		(20 "In9.Cu" signal "L10")
		(22 "In10.Cu" signal "L11GND")
		(24 "In11.Cu" signal "L12")
		(26 "In12.Cu" signal "L13GND")
		(2 "B.Cu" signal "BOTTOM")
		(9 "F.Adhes" user "F.Adhesive")
		(11 "B.Adhes" user "B.Adhesive")
		(13 "F.Paste" user "Package Geometry/Pastemask Top")
		(15 "B.Paste" user "Package Geometry/Pastemask Bottom")
		(5 "F.SilkS" user "Ref Des/Silkscreen Top")
		(7 "B.SilkS" user "Ref Des/Silkscreen Bottom")
		(1 "F.Mask" user "Board Geometry/Soldermask Top")
		(3 "B.Mask" user "Board Geometry/Soldermask Bottom")
		(17 "Dwgs.User" user "User.Drawings")
		(19 "Cmts.User" user "User.Comments")
		(21 "Eco1.User" user "User.Eco1")
		(23 "Eco2.User" user "User.Eco2")
		(25 "Edge.Cuts" user "Board Geometry/Outline")
		(27 "Margin" user)
		(31 "F.CrtYd" user "Package Geometry/Place Bound Top")
		(29 "B.CrtYd" user "Package Geometry/Place Bound Bottom")
		(35 "F.Fab" user "Ref Des/Assembly Top")
		(33 "B.Fab" user "Ref Des/Assembly Bottom")
	)
	(footprint ""
		(layer "B.Cu")
		(at 348.713806 -61.257434)
		(property "Reference" "C2U14"
			(at 0 0 0)
			(layer "B.SilkS")
			(hide yes)
			(effects
				(font
					(size 1.27 1.27)
				)
				(justify mirror)
			)
		)
		(property "Value" ""
			(at 0 0 0)
			(layer "B.Fab")
			(effects
				(font
					(size 1.27 1.27)
				)
				(justify mirror)
			)
		)
		(duplicate_pad_numbers_are_jumpers no)
		(fp_poly
			(pts
				(xy -0.3048 -0.1016) (xy -0.3048 0.9906) (xy 0.3048 0.9906) (xy 0.3048 -0.1016)
			)
			(stroke
				(width 0)
				(type default)
			)
			(fill no)
			(layer "B.CrtYd")
		)
		(fp_line
			(start -0.3048 -0.1016)
			(end 0.3048 -0.1016)
			(stroke
				(width 0.1)
				(type default)
			)
			(layer "B.Fab")
		)
		(fp_line
			(start -0.3048 0.9906)
			(end -0.3048 -0.1016)
			(stroke
				(width 0.1)
				(type default)
			)
			(layer "B.Fab")
		)
		(fp_line
			(start 0.3048 -0.1016)
			(end 0.3048 0.9906)
			(stroke
				(width 0.1)
				(type default)
			)
			(layer "B.Fab")
		)
		(fp_line
			(start 0.3048 0.9906)
			(end -0.3048 0.9906)
			(stroke
				(width 0.1)
				(type default)
			)
			(layer "B.Fab")
		)
		(pad "1" smd rect
			(at 0 0 180)
			(size 0.508 0.508)
			(layers "B.Cu" "B.Mask" "B.Paste")
			(net "P3E_CPU0_PE1_PCH_RXN<5>")
		)
		(pad "2" smd rect
			(at 0 0.889 180)
			(size 0.508 0.508)
			(layers "B.Cu" "B.Mask" "B.Paste")
			(net "P3E_CPU0_PE1_SS_RXN<5>")
		)
		(zone
			(layer "B.Cu")
			(hatch none 0.5)
			(connect_pads
				(clearance 0)
			)
			(min_thickness 0.25)
			(keepout
				(tracks allowed)
				(vias not_allowed)
				(pads allowed)
				(copperpour not_allowed)
				(footprints allowed)
			)
			(placement
				(enabled no)
				(sheetname "")
			)
			(fill
				(thermal_gap 0.5)
				(thermal_bridge_width 0.5)
				(island_removal_mode 0)
			)
			(polygon
				(pts
					(xy 348.967806 -61.003434) (xy 348.459806 -61.003434) (xy 348.459806 -60.622434) (xy 348.967806 -60.622434)
				)
			)
		)
	)
	(footprint ""
		(layer "B.Cu")
		(at 197.866 -100.584 90)
		(property "Reference" "C6N2"
			(at 0 0 90)
			(layer "B.SilkS")
			(hide yes)
			(effects
				(font
					(size 1.27 1.27)
				)
				(justify mirror)
			)
		)
		(property "Value" ""
			(at 0 0 90)
			(layer "B.Fab")
			(effects
				(font
					(size 1.27 1.27)
				)
				(justify mirror)
			)
		)
		(duplicate_pad_numbers_are_jumpers no)
		(fp_rect
			(start -0.7239 -0.2159)
			(end 0.7239 1.9939)
			(stroke
				(width 0)
				(type default)
			)
			(fill no)
			(layer "B.CrtYd")
		)
		(fp_line
			(start 0.7239 -0.2159)
			(end 0.7239 1.9939)
			(stroke
				(width 0.1)
				(type default)
			)
			(layer "B.Fab")
		)
		(fp_line
			(start -0.7239 -0.2159)
			(end 0.7239 -0.2159)
			(stroke
				(width 0.1)
				(type default)
			)
			(layer "B.Fab")
		)
		(fp_line
			(start 0.7239 1.9939)
			(end -0.7239 1.9939)
			(stroke
				(width 0.1)
				(type default)
			)
			(layer "B.Fab")
		)
		(fp_line
			(start -0.7239 1.9939)
			(end -0.7239 -0.2159)
			(stroke
				(width 0.1)
				(type default)
			)
			(layer "B.Fab")
		)
		(pad "1" smd rect
			(at 0 0 270)
			(size 1.27 1.016)
			(layers "B.Cu" "B.Mask" "B.Paste")
			(net "VR_FET_SW_P12V_STBY_PVCCIN_CPU0")
		)
		(pad "2" smd rect
			(at 0 1.778 270)
			(size 1.27 1.016)
			(layers "B.Cu" "B.Mask" "B.Paste")
			(net "GND")
		)
		(zone
			(layer "B.Cu")
			(hatch none 0.5)
			(connect_pads
				(clearance 0)
			)
			(min_thickness 0.25)
			(keepout
				(tracks not_allowed)
				(vias allowed)
				(pads allowed)
				(copperpour not_allowed)
				(footprints allowed)
			)
			(placement
				(enabled no)
				(sheetname "")
			)
			(fill
				(thermal_gap 0.5)
				(thermal_bridge_width 0.5)
				(island_removal_mode 0)
			)
			(polygon
				(pts
					(xy 198.374 -99.949) (xy 199.136 -99.949) (xy 199.136 -101.219) (xy 198.374 -101.219)
				)
			)
		)
	)
	(footprint ""
		(layer "B.Cu")
		(at 111.000032 -140.208 90)
		(property "Reference" "C5G109"
			(at -1.14681 0.76708 180)
			(unlocked yes)
			(layer "B.SilkS")
			(effects
				(font
					(size 0.7874 0.5842)
					(thickness 0.1524)
				)
				(justify mirror)
			)
		)
		(property "Value" ""
			(at 0 0 90)
			(layer "B.Fab")
			(effects
				(font
					(size 1.27 1.27)
				)
				(justify mirror)
			)
		)
		(duplicate_pad_numbers_are_jumpers no)
		(fp_rect
			(start -0.4953 -0.2032)
			(end 0.4953 1.6002)
			(stroke
				(width 0)
				(type default)
			)
			(fill no)
			(layer "B.CrtYd")
		)
		(fp_line
			(start 0.4953 -0.2032)
			(end -0.4953 -0.2032)
			(stroke
				(width 0.1)
				(type default)
			)
			(layer "B.Fab")
		)
		(fp_line
			(start -0.4953 -0.2032)
			(end -0.4953 1.6002)
			(stroke
				(width 0.1)
				(type default)
			)
			(layer "B.Fab")
		)
		(fp_line
			(start 0.4953 1.6002)
			(end 0.4953 -0.2032)
			(stroke
				(width 0.1)
				(type default)
			)
			(layer "B.Fab")
		)
		(fp_line
			(start -0.4953 1.6002)
			(end 0.4953 1.6002)
			(stroke
				(width 0.1)
				(type default)
			)
			(layer "B.Fab")
		)
		(pad "1" smd rect
			(at 0 0 270)
			(size 0.762 0.889)
			(layers "B.Cu" "B.Mask" "B.Paste")
			(net "PVDDQ_KLM")
		)
		(pad "2" smd rect
			(at 0 1.397 270)
			(size 0.762 0.889)
			(layers "B.Cu" "B.Mask" "B.Paste")
			(net "GND")
		)
		(zone
			(layer "B.Cu")
			(hatch none 0.5)
			(connect_pads
				(clearance 0)
			)
			(min_thickness 0.25)
			(keepout
				(tracks not_allowed)
				(vias allowed)
				(pads allowed)
				(copperpour not_allowed)
				(footprints allowed)
			)
			(placement
				(enabled no)
				(sheetname "")
			)
			(fill
				(thermal_gap 0.5)
				(thermal_bridge_width 0.5)
				(island_removal_mode 0)
			)
			(polygon
				(pts
					(xy 111.444532 -139.827) (xy 111.952532 -139.827) (xy 111.952532 -140.589) (xy 111.444532 -140.589)
				)
			)
		)
	)
)
